(kicad_pcb
	(version 20260206)
	(generator "pcbnew")
	(generator_version "10.0")
	(general
		(thickness 1.6)
		(legacy_teardrops no)
	)
	(paper "A4")
	(title_block
		(title "Bryce Canyon_R.DPB_16317-1_OCP.brd")
		(comment 1 "Bryce Canyon / footprints 1626-1633 of 2099")
	)
	(layers
		(0 "F.Cu" signal "TOP")
		(4 "In1.Cu" signal "L2GND")
		(6 "In2.Cu" signal "L3")
		(8 "In3.Cu" signal "L4VCC")
		(10 "In4.Cu" signal "L5VCC")
		(12 "In5.Cu" signal "L6")
		(14 "In6.Cu" signal "L7GND")
		(2 "B.Cu" signal "BOTTOM")
		(9 "F.Adhes" user "F.Adhesive")
		(11 "B.Adhes" user "B.Adhesive")
		(13 "F.Paste" user "Package Geometry/Pastemask Top")
		(15 "B.Paste" user "Package Geometry/Pastemask Bottom")
		(5 "F.SilkS" user "Ref Des/Silkscreen Top")
		(7 "B.SilkS" user "Ref Des/Silkscreen Bottom")
		(1 "F.Mask" user "Board Geometry/Soldermask Top")
		(3 "B.Mask" user "Board Geometry/Soldermask Bottom")
		(17 "Dwgs.User" user "User.Drawings")
		(19 "Cmts.User" user "User.Comments")
		(21 "Eco1.User" user "User.Eco1")
		(23 "Eco2.User" user "User.Eco2")
		(25 "Edge.Cuts" user "Board Geometry/Outline")
		(27 "Margin" user)
		(31 "F.CrtYd" user "Package Geometry/Place Bound Top")
		(29 "B.CrtYd" user "Package Geometry/Place Bound Bottom")
		(35 "F.Fab" user "Ref Des/Assembly Top")
		(33 "B.Fab" user "Ref Des/Assembly Bottom")
	)
	(footprint ""
		(layer "F.Cu")
		(at 140.97 -265.684 -90)
		(property "Reference" "C86"
			(at 0 0 270)
			(layer "F.SilkS")
			(hide yes)
			(effects
				(font
					(size 1.27 1.27)
				)
			)
		)
		(property "Value" "SC4D7U25V5KX-1-GP"
			(at -0.0762 -6.1214 270)
			(unlocked yes)
			(layer "F.Fab")
			(hide yes)
			(effects
				(font
					(size 1.016 1.016)
					(thickness 0.1524)
				)
			)
		)
		(property "Device Type" "C805H58"
			(at -0.0762 -8.1534 270)
			(unlocked yes)
			(layer "F.Fab")
			(hide yes)
			(effects
				(font
					(size 1.016 1.016)
					(thickness 0.1524)
				)
			)
		)
		(duplicate_pad_numbers_are_jumpers no)
		(fp_line
			(start 0.635 0)
			(end -0.635 0)
			(stroke
				(width 0.508)
				(type default)
			)
			(layer "F.SilkS")
		)
		(fp_rect
			(start -0.9652 1.778)
			(end 0.9652 -1.778)
			(stroke
				(width 0)
				(type default)
			)
			(fill no)
			(layer "F.CrtYd")
		)
		(fp_poly
			(pts
				(xy -0.9652 -1.778) (xy 0.9652 -1.778) (xy 0.9652 1.778) (xy -0.9652 1.778)
			)
			(stroke
				(width 0)
				(type default)
			)
			(fill no)
			(layer "F.Fab")
		)
		(pad "1" smd rect
			(at 0 -0.9652 270)
			(size 1.397 1.143)
			(layers "F.Cu" "F.Mask" "F.Paste")
			(net "P12V_HDD4")
		)
		(pad "2" smd rect
			(at 0 0.9652 270)
			(size 1.397 1.143)
			(layers "F.Cu" "F.Mask" "F.Paste")
			(net "GND")
		)
	)
	(footprint ""
		(layer "F.Cu")
		(at 22.5044 -131.2672 -90)
		(property "Reference" "R358"
			(at 0 0 270)
			(layer "F.SilkS")
			(hide yes)
			(effects
				(font
					(size 1.27 1.27)
				)
			)
		)
		(property "Value" "0R2J-2-GP"
			(at 0.064008 -3.993896 270)
			(unlocked yes)
			(layer "F.Fab")
			(hide yes)
			(effects
				(font
					(size 1.016 1.016)
					(thickness 0.1524)
				)
			)
		)
		(property "Device Type" "R402H16"
			(at 0.064008 -5.517896 270)
			(unlocked yes)
			(layer "F.Fab")
			(hide yes)
			(effects
				(font
					(size 1.016 1.016)
					(thickness 0.1524)
				)
			)
		)
		(duplicate_pad_numbers_are_jumpers no)
		(fp_line
			(start -0.508 -0.9398)
			(end -0.508 0.9398)
			(stroke
				(width 0.1524)
				(type default)
			)
			(layer "F.SilkS")
		)
		(fp_line
			(start 0.508 -0.9398)
			(end -0.508 -0.9398)
			(stroke
				(width 0.1524)
				(type default)
			)
			(layer "F.SilkS")
		)
		(fp_rect
			(start -0.508 0.9398)
			(end 0.508 -0.9398)
			(stroke
				(width 0)
				(type default)
			)
			(fill no)
			(layer "F.CrtYd")
		)
		(fp_rect
			(start -0.508 0.9398)
			(end 0.508 -0.9398)
			(stroke
				(width 0)
				(type default)
			)
			(fill no)
			(layer "F.Fab")
		)
		(pad "1" smd custom
			(at 0 -0.4445 270)
			(size 0.1397 0.1397)
			(layers "F.Cu" "F.Mask" "F.Paste")
			(net "DRIVE_B_12_PWR")
			(options
				(clearance outline)
				(anchor circle)
			)
			(primitives
				(gr_poly
					(pts
						(arc
							(start -0.1778 -0.2794)
							(mid -0.249642 -0.249642)
							(end -0.2794 -0.1778)
						)
						(arc
							(start -0.2794 0.1778)
							(mid -0.249642 0.249642)
							(end -0.1778 0.2794)
						)
						(arc
							(start 0.1778 0.2794)
							(mid 0.249642 0.249642)
							(end 0.2794 0.1778)
						)
						(arc
							(start 0.2794 -0.1778)
							(mid 0.249642 -0.249642)
							(end 0.1778 -0.2794)
						)
					)
					(width 0)
					(fill yes)
				)
			)
		)
		(pad "2" smd custom
			(at 0 0.4445 270)
			(size 0.1397 0.1397)
			(layers "F.Cu" "F.Mask" "F.Paste")
			(net "SW_PWR_R_HDD12")
			(options
				(clearance outline)
				(anchor circle)
			)
			(primitives
				(gr_poly
					(pts
						(arc
							(start -0.1778 -0.2794)
							(mid -0.249642 -0.249642)
							(end -0.2794 -0.1778)
						)
						(arc
							(start -0.2794 0.1778)
							(mid -0.249642 0.249642)
							(end -0.1778 0.2794)
						)
						(arc
							(start 0.1778 0.2794)
							(mid 0.249642 0.249642)
							(end 0.2794 0.1778)
						)
						(arc
							(start 0.2794 -0.1778)
							(mid 0.249642 -0.249642)
							(end 0.1778 -0.2794)
						)
					)
					(width 0)
					(fill yes)
				)
			)
		)
	)
	(footprint ""
		(layer "F.Cu")
		(at 273.5834 -331.34173 90)
		(property "Reference" "R90"
			(at 0 0 90)
			(layer "F.SilkS")
			(hide yes)
			(effects
				(font
					(size 1.27 1.27)
				)
			)
		)
		(property "Value" "4K7R2F-GP"
			(at 0.064008 -3.993896 90)
			(unlocked yes)
			(layer "F.Fab")
			(hide yes)
			(effects
				(font
					(size 1.016 1.016)
					(thickness 0.1524)
				)
			)
		)
		(property "Device Type" "R402H16"
			(at 0.064008 -5.517896 90)
			(unlocked yes)
			(layer "F.Fab")
			(hide yes)
			(effects
				(font
					(size 1.016 1.016)
					(thickness 0.1524)
				)
			)
		)
		(duplicate_pad_numbers_are_jumpers no)
		(fp_line
			(start 0.508 -0.9398)
			(end -0.508 -0.9398)
			(stroke
				(width 0.1524)
				(type default)
			)
			(layer "F.SilkS")
		)
		(fp_line
			(start -0.508 -0.9398)
			(end -0.508 0.9398)
			(stroke
				(width 0.1524)
				(type default)
			)
			(layer "F.SilkS")
		)
		(fp_rect
			(start -0.508 0.9398)
			(end 0.508 -0.9398)
			(stroke
				(width 0)
				(type default)
			)
			(fill no)
			(layer "F.CrtYd")
		)
		(fp_rect
			(start -0.508 0.9398)
			(end 0.508 -0.9398)
			(stroke
				(width 0)
				(type default)
			)
			(fill no)
			(layer "F.Fab")
		)
		(pad "1" smd custom
			(at 0 -0.4445 90)
			(size 0.1397 0.1397)
			(layers "F.Cu" "F.Mask" "F.Paste")
			(net "P3V3_IN")
			(options
				(clearance outline)
				(anchor circle)
			)
			(primitives
				(gr_poly
					(pts
						(arc
							(start -0.1778 -0.2794)
							(mid -0.249642 -0.249642)
							(end -0.2794 -0.1778)
						)
						(arc
							(start -0.2794 0.1778)
							(mid -0.249642 0.249642)
							(end -0.1778 0.2794)
						)
						(arc
							(start 0.1778 0.2794)
							(mid 0.249642 0.249642)
							(end 0.2794 0.1778)
						)
						(arc
							(start 0.2794 -0.1778)
							(mid 0.249642 -0.249642)
							(end 0.1778 -0.2794)
						)
					)
					(width 0)
					(fill yes)
				)
			)
		)
		(pad "2" smd custom
			(at 0 0.4445 90)
			(size 0.1397 0.1397)
			(layers "F.Cu" "F.Mask" "F.Paste")
			(net "PWM_OUT_FAN1")
			(options
				(clearance outline)
				(anchor circle)
			)
			(primitives
				(gr_poly
					(pts
						(arc
							(start -0.1778 -0.2794)
							(mid -0.249642 -0.249642)
							(end -0.2794 -0.1778)
						)
						(arc
							(start -0.2794 0.1778)
							(mid -0.249642 0.249642)
							(end -0.1778 0.2794)
						)
						(arc
							(start 0.1778 0.2794)
							(mid 0.249642 0.249642)
							(end 0.2794 0.1778)
						)
						(arc
							(start 0.2794 -0.1778)
							(mid 0.249642 -0.249642)
							(end 0.1778 -0.2794)
						)
					)
					(width 0)
					(fill yes)
				)
			)
		)
	)
	(footprint ""
		(layer "F.Cu")
		(at 236.22 -192.86728 90)
		(property "Reference" "C15"
			(at 0 0 90)
			(layer "F.SilkS")
			(hide yes)
			(effects
				(font
					(size 1.27 1.27)
				)
			)
		)
		(property "Value" "SC1U16V3KX-5GP"
			(at 0 -2.8194 90)
			(unlocked yes)
			(layer "F.Fab")
			(hide yes)
			(effects
				(font
					(size 1.016 1.016)
					(thickness 0.1524)
				)
			)
		)
		(property "Device Type" "C603H36"
			(at 0 -4.3434 90)
			(unlocked yes)
			(layer "F.Fab")
			(hide yes)
			(effects
				(font
					(size 1.016 1.016)
					(thickness 0.1524)
				)
			)
		)
		(duplicate_pad_numbers_are_jumpers no)
		(fp_line
			(start 0.508 0)
			(end -0.508 0)
			(stroke
				(width 0.2032)
				(type default)
			)
			(layer "F.SilkS")
		)
		(fp_rect
			(start -0.5842 1.3335)
			(end 0.5842 -1.3335)
			(stroke
				(width 0)
				(type default)
			)
			(fill no)
			(layer "F.CrtYd")
		)
		(fp_rect
			(start -0.5842 1.3335)
			(end 0.5842 -1.3335)
			(stroke
				(width 0)
				(type default)
			)
			(fill no)
			(layer "F.Fab")
		)
		(pad "1" smd custom
			(at 0 -0.762 90)
			(size 0.2159 0.2159)
			(layers "F.Cu" "F.Mask" "F.Paste")
			(net "GPIO_VCC_U9")
			(options
				(clearance outline)
				(anchor circle)
			)
			(primitives
				(gr_poly
					(pts
						(arc
							(start -0.3302 -0.4318)
							(mid -0.402042 -0.402042)
							(end -0.4318 -0.3302)
						)
						(arc
							(start -0.4318 0.3302)
							(mid -0.402042 0.402042)
							(end -0.3302 0.4318)
						)
						(arc
							(start 0.3302 0.4318)
							(mid 0.402042 0.402042)
							(end 0.4318 0.3302)
						)
						(arc
							(start 0.4318 -0.3302)
							(mid 0.402042 -0.402042)
							(end 0.3302 -0.4318)
						)
					)
					(width 0)
					(fill yes)
				)
			)
		)
		(pad "2" smd custom
			(at 0 0.762 90)
			(size 0.2159 0.2159)
			(layers "F.Cu" "F.Mask" "F.Paste")
			(net "GND")
			(options
				(clearance outline)
				(anchor circle)
			)
			(primitives
				(gr_poly
					(pts
						(arc
							(start -0.3302 -0.4318)
							(mid -0.402042 -0.402042)
							(end -0.4318 -0.3302)
						)
						(arc
							(start -0.4318 0.3302)
							(mid -0.402042 0.402042)
							(end -0.3302 0.4318)
						)
						(arc
							(start 0.3302 0.4318)
							(mid 0.402042 0.402042)
							(end 0.4318 0.3302)
						)
						(arc
							(start 0.4318 -0.3302)
							(mid 0.402042 -0.402042)
							(end 0.3302 -0.4318)
						)
					)
					(width 0)
					(fill yes)
				)
			)
		)
	)
	(footprint ""
		(layer "F.Cu")
		(at 348.546166 -364.24743 90)
		(property "Reference" "C532"
			(at 0 0 90)
			(layer "F.SilkS")
			(hide yes)
			(effects
				(font
					(size 1.27 1.27)
				)
			)
		)
		(property "Value" "SCD1U25V2KX-2-GP"
			(at 1.1811 -2.7051 90)
			(unlocked yes)
			(layer "F.Fab")
			(hide yes)
			(effects
				(font
					(size 1.016 1.016)
					(thickness 0.1524)
				)
			)
		)
		(property "Device Type" "C402H22"
			(at 1.1811 -4.2291 90)
			(unlocked yes)
			(layer "F.Fab")
			(hide yes)
			(effects
				(font
					(size 1.016 1.016)
					(thickness 0.1524)
				)
			)
		)
		(duplicate_pad_numbers_are_jumpers no)
		(fp_rect
			(start -0.4318 0.9525)
			(end 0.4318 -0.9525)
			(stroke
				(width 0)
				(type default)
			)
			(fill no)
			(layer "F.CrtYd")
		)
		(fp_rect
			(start -0.4318 0.9525)
			(end 0.4318 -0.9525)
			(stroke
				(width 0)
				(type default)
			)
			(fill no)
			(layer "F.Fab")
		)
		(pad "1" smd custom
			(at 0 -0.4445 90)
			(size 0.1524 0.1524)
			(layers "F.Cu" "F.Mask" "F.Paste")
			(net "P12V_FAN2")
			(options
				(clearance outline)
				(anchor circle)
			)
			(primitives
				(gr_poly
					(pts
						(arc
							(start 0.3048 -0.2032)
							(mid 0.275042 -0.275042)
							(end 0.2032 -0.3048)
						)
						(arc
							(start -0.2032 -0.3048)
							(mid -0.275042 -0.275042)
							(end -0.3048 -0.2032)
						)
						(arc
							(start -0.3048 0.2032)
							(mid -0.275042 0.275042)
							(end -0.2032 0.3048)
						)
						(arc
							(start 0.2032 0.3048)
							(mid 0.275042 0.275042)
							(end 0.3048 0.2032)
						)
					)
					(width 0)
					(fill yes)
				)
			)
		)
		(pad "2" smd custom
			(at 0 0.4445 90)
			(size 0.1524 0.1524)
			(layers "F.Cu" "F.Mask" "F.Paste")
			(net "GND")
			(options
				(clearance outline)
				(anchor circle)
			)
			(primitives
				(gr_poly
					(pts
						(arc
							(start 0.3048 -0.2032)
							(mid 0.275042 -0.275042)
							(end 0.2032 -0.3048)
						)
						(arc
							(start -0.2032 -0.3048)
							(mid -0.275042 -0.275042)
							(end -0.3048 -0.2032)
						)
						(arc
							(start -0.3048 0.2032)
							(mid -0.275042 0.275042)
							(end -0.2032 0.3048)
						)
						(arc
							(start 0.2032 0.3048)
							(mid 0.275042 0.275042)
							(end 0.3048 0.2032)
						)
					)
					(width 0)
					(fill yes)
				)
			)
		)
	)
	(footprint ""
		(layer "F.Cu")
		(at 315.849 -98.171)
		(property "Reference" "R428"
			(at 0 0 0)
			(layer "F.SilkS")
			(hide yes)
			(effects
				(font
					(size 1.27 1.27)
				)
			)
		)
		(property "Value" "130R3F-GP"
			(at -0.0254 -2.5146 0)
			(unlocked yes)
			(layer "F.Fab")
			(hide yes)
			(effects
				(font
					(size 1.016 1.016)
					(thickness 0.1524)
				)
			)
		)
		(property "Device Type" "R603H22"
			(at -0.0254 -4.0386 0)
			(unlocked yes)
			(layer "F.Fab")
			(hide yes)
			(effects
				(font
					(size 1.016 1.016)
					(thickness 0.1524)
				)
			)
		)
		(duplicate_pad_numbers_are_jumpers no)
		(fp_line
			(start -0.4826 0)
			(end -0.2032 0)
			(stroke
				(width 0.2032)
				(type default)
			)
			(layer "F.SilkS")
		)
		(fp_line
			(start 0.2032 0)
			(end 0.4826 0)
			(stroke
				(width 0.2032)
				(type default)
			)
			(layer "F.SilkS")
		)
		(fp_rect
			(start -0.5842 1.3335)
			(end 0.5842 -1.3335)
			(stroke
				(width 0)
				(type default)
			)
			(fill no)
			(layer "F.CrtYd")
		)
		(fp_rect
			(start -0.5842 1.3335)
			(end 0.5842 -1.3335)
			(stroke
				(width 0)
				(type default)
			)
			(fill no)
			(layer "F.Fab")
		)
		(pad "1" smd custom
			(at 0 -0.762)
			(size 0.2159 0.2159)
			(layers "F.Cu" "F.Mask" "F.Paste")
			(net "P5V_B_3")
			(options
				(clearance outline)
				(anchor circle)
			)
			(primitives
				(gr_poly
					(pts
						(arc
							(start -0.3302 -0.4318)
							(mid -0.402042 -0.402042)
							(end -0.4318 -0.3302)
						)
						(arc
							(start -0.4318 0.3302)
							(mid -0.402042 0.402042)
							(end -0.3302 0.4318)
						)
						(arc
							(start 0.3302 0.4318)
							(mid 0.402042 0.402042)
							(end 0.4318 0.3302)
						)
						(arc
							(start 0.4318 -0.3302)
							(mid 0.402042 -0.402042)
							(end 0.3302 -0.4318)
						)
					)
					(width 0)
					(fill yes)
				)
			)
		)
		(pad "2" smd custom
			(at 0 0.762)
			(size 0.2159 0.2159)
			(layers "F.Cu" "F.Mask" "F.Paste")
			(net "FLT_HDD18")
			(options
				(clearance outline)
				(anchor circle)
			)
			(primitives
				(gr_poly
					(pts
						(arc
							(start -0.3302 -0.4318)
							(mid -0.402042 -0.402042)
							(end -0.4318 -0.3302)
						)
						(arc
							(start -0.4318 0.3302)
							(mid -0.402042 0.402042)
							(end -0.3302 0.4318)
						)
						(arc
							(start 0.3302 0.4318)
							(mid 0.402042 0.402042)
							(end 0.4318 0.3302)
						)
						(arc
							(start 0.4318 -0.3302)
							(mid 0.402042 -0.402042)
							(end 0.3302 -0.4318)
						)
					)
					(width 0)
					(fill yes)
				)
			)
		)
	)
	(footprint ""
		(layer "F.Cu")
		(at 396.7734 -270.637 -90)
		(property "Reference" "R288"
			(at 0 0 270)
			(layer "F.SilkS")
			(hide yes)
			(effects
				(font
					(size 1.27 1.27)
				)
			)
		)
		(property "Value" "2R6F-GP"
			(at -0.0508 -4.8514 270)
			(unlocked yes)
			(layer "F.Fab")
			(hide yes)
			(effects
				(font
					(size 1.016 1.016)
					(thickness 0.1524)
				)
			)
		)
		(property "Device Type" "R1206H26"
			(at 0 -6.3754 270)
			(unlocked yes)
			(layer "F.Fab")
			(hide yes)
			(effects
				(font
					(size 1.016 1.016)
					(thickness 0.1524)
				)
			)
		)
		(duplicate_pad_numbers_are_jumpers no)
		(fp_line
			(start -1.016 2.2352)
			(end -1.016 -2.2352)
			(stroke
				(width 0.1524)
				(type default)
			)
			(layer "F.SilkS")
		)
		(fp_line
			(start 1.016 2.2352)
			(end -1.016 2.2352)
			(stroke
				(width 0.1524)
				(type default)
			)
			(layer "F.SilkS")
		)
		(fp_line
			(start -1.016 -2.2352)
			(end 1.016 -2.2352)
			(stroke
				(width 0.1524)
				(type default)
			)
			(layer "F.SilkS")
		)
		(fp_line
			(start 1.016 -2.2352)
			(end 1.016 2.2352)
			(stroke
				(width 0.1524)
				(type default)
			)
			(layer "F.SilkS")
		)
		(fp_rect
			(start -1.0922 2.3114)
			(end 1.0922 -2.3114)
			(stroke
				(width 0)
				(type default)
			)
			(fill no)
			(layer "F.CrtYd")
		)
		(fp_poly
			(pts
				(xy -1.0922 -2.3114) (xy 1.0922 -2.3114) (xy 1.0922 2.3114) (xy -1.0922 2.3114)
			)
			(stroke
				(width 0)
				(type default)
			)
			(fill no)
			(layer "F.Fab")
		)
		(pad "1" smd rect
			(at 0 -1.397 270)
			(size 1.651 1.27)
			(layers "F.Cu" "F.Mask" "F.Paste")
			(net "P12V_HDD8")
		)
		(pad "2" smd rect
			(at 0 1.397 270)
			(size 1.651 1.27)
			(layers "F.Cu" "F.Mask" "F.Paste")
			(net "12V_PRE_8")
		)
	)
	(footprint ""
		(layer "F.Cu")
		(at 371.801644 -97.390204 -90)
		(property "Reference" "R479"
			(at 0 0 270)
			(layer "F.SilkS")
			(hide yes)
			(effects
				(font
					(size 1.27 1.27)
				)
			)
		)
		(property "Value" "4K7R2F-GP"
			(at 0.064008 -3.993896 270)
			(unlocked yes)
			(layer "F.Fab")
			(hide yes)
			(effects
				(font
					(size 1.016 1.016)
					(thickness 0.1524)
				)
			)
		)
		(property "Device Type" "R402H16"
			(at 0.064008 -5.517896 270)
			(unlocked yes)
			(layer "F.Fab")
			(hide yes)
			(effects
				(font
					(size 1.016 1.016)
					(thickness 0.1524)
				)
			)
		)
		(duplicate_pad_numbers_are_jumpers no)
		(fp_line
			(start -0.508 -0.9398)
			(end -0.508 0.9398)
			(stroke
				(width 0.1524)
				(type default)
			)
			(layer "F.SilkS")
		)
		(fp_line
			(start 0.508 -0.9398)
			(end -0.508 -0.9398)
			(stroke
				(width 0.1524)
				(type default)
			)
			(layer "F.SilkS")
		)
		(fp_rect
			(start -0.508 0.9398)
			(end 0.508 -0.9398)
			(stroke
				(width 0)
				(type default)
			)
			(fill no)
			(layer "F.CrtYd")
		)
		(fp_rect
			(start -0.508 0.9398)
			(end 0.508 -0.9398)
			(stroke
				(width 0)
				(type default)
			)
			(fill no)
			(layer "F.Fab")
		)
		(pad "1" smd custom
			(at 0 -0.4445 270)
			(size 0.1397 0.1397)
			(layers "F.Cu" "F.Mask" "F.Paste")
			(net "DRIVE_B_20_ACT")
			(options
				(clearance outline)
				(anchor circle)
			)
			(primitives
				(gr_poly
					(pts
						(arc
							(start -0.1778 -0.2794)
							(mid -0.249642 -0.249642)
							(end -0.2794 -0.1778)
						)
						(arc
							(start -0.2794 0.1778)
							(mid -0.249642 0.249642)
							(end -0.1778 0.2794)
						)
						(arc
							(start 0.1778 0.2794)
							(mid 0.249642 0.249642)
							(end 0.2794 0.1778)
						)
						(arc
							(start 0.2794 -0.1778)
							(mid 0.249642 -0.249642)
							(end 0.1778 -0.2794)
						)
					)
					(width 0)
					(fill yes)
				)
			)
		)
		(pad "2" smd custom
			(at 0 0.4445 270)
			(size 0.1397 0.1397)
			(layers "F.Cu" "F.Mask" "F.Paste")
			(net "GND")
			(options
				(clearance outline)
				(anchor circle)
			)
			(primitives
				(gr_poly
					(pts
						(arc
							(start -0.1778 -0.2794)
							(mid -0.249642 -0.249642)
							(end -0.2794 -0.1778)
						)
						(arc
							(start -0.2794 0.1778)
							(mid -0.249642 0.249642)
							(end -0.1778 0.2794)
						)
						(arc
							(start 0.1778 0.2794)
							(mid 0.249642 0.249642)
							(end 0.2794 0.1778)
						)
						(arc
							(start 0.2794 -0.1778)
							(mid 0.249642 -0.249642)
							(end 0.1778 -0.2794)
						)
					)
					(width 0)
					(fill yes)
				)
			)
		)
	)
)
